(kicad_pcb
	(version 20260206)
	(generator "pcbnew")
	(generator_version "10.0")
	(general
		(thickness 1.6)
		(legacy_teardrops no)
	)
	(paper "A4")
	(title_block
		(title "baseboard — 13948-1b.1110WZS1818.brd")
		(comment 1 "Honey Badger (Wiwynn) / footprints 2247-2255 of 2523")
	)
	(layers
		(0 "F.Cu" signal "TOP")
		(4 "In1.Cu" signal "L2GND")
		(6 "In2.Cu" signal "L3")
		(8 "In3.Cu" signal "L4VCC")
		(10 "In4.Cu" signal "L5VCC")
		(12 "In5.Cu" signal "L6")
		(14 "In6.Cu" signal "L7GND")
		(2 "B.Cu" signal "BOTTOM")
		(9 "F.Adhes" user "F.Adhesive")
		(11 "B.Adhes" user "B.Adhesive")
		(13 "F.Paste" user "Package Geometry/Pastemask Top")
		(15 "B.Paste" user "Package Geometry/Pastemask Bottom")
		(5 "F.SilkS" user "Ref Des/Silkscreen Top")
		(7 "B.SilkS" user "Ref Des/Silkscreen Bottom")
		(1 "F.Mask" user "Board Geometry/Soldermask Top")
		(3 "B.Mask" user "Board Geometry/Soldermask Bottom")
		(17 "Dwgs.User" user "User.Drawings")
		(19 "Cmts.User" user "User.Comments")
		(21 "Eco1.User" user "User.Eco1")
		(23 "Eco2.User" user "User.Eco2")
		(25 "Edge.Cuts" user "Board Geometry/Outline")
		(27 "Margin" user)
		(31 "F.CrtYd" user "Package Geometry/Place Bound Top")
		(29 "B.CrtYd" user "Package Geometry/Place Bound Bottom")
		(35 "F.Fab" user "Ref Des/Assembly Top")
		(33 "B.Fab" user "Ref Des/Assembly Bottom")
	)
	(footprint ""
		(layer "B.Cu")
		(at 90.81516 -50.673)
		(property "Reference" "STP7"
			(at 0 0 0)
			(layer "B.SilkS")
			(hide yes)
			(effects
				(font
					(size 1.27 1.27)
				)
				(justify mirror)
			)
		)
		(property "Value" "TPAD28"
			(at -0.0127 -1.8034 0)
			(unlocked yes)
			(layer "B.Fab")
			(hide yes)
			(effects
				(font
					(size 1.016 1.016)
					(thickness 0.1524)
				)
				(justify mirror)
			)
		)
		(property "Device Type" "TPAD28"
			(at -0.0127 -3.3274 0)
			(unlocked yes)
			(layer "B.Fab")
			(hide yes)
			(effects
				(font
					(size 1.016 1.016)
					(thickness 0.1524)
				)
				(justify mirror)
			)
		)
		(duplicate_pad_numbers_are_jumpers no)
		(fp_poly
			(pts
				(arc
					(start 0.3556 0)
					(mid -0.3556 0)
					(end 0.3556 0)
				)
			)
			(stroke
				(width 0)
				(type default)
			)
			(fill no)
			(layer "B.CrtYd")
		)
		(fp_poly
			(pts
				(arc
					(start 0.6096 0)
					(mid -0.6096 0)
					(end 0.6096 0)
				)
			)
			(stroke
				(width 0)
				(type default)
			)
			(fill no)
			(layer "B.Fab")
		)
		(pad "1" smd circle
			(at 0 0 180)
			(size 0.7112 0.7112)
			(layers "B.Cu" "B.Mask" "B.Paste")
			(net "SIO_DOUT_0")
		)
	)
	(footprint ""
		(layer "B.Cu")
		(at 103.740966 -55.8038)
		(property "Reference" "STP61"
			(at 0 0 0)
			(layer "B.SilkS")
			(hide yes)
			(effects
				(font
					(size 1.27 1.27)
				)
				(justify mirror)
			)
		)
		(property "Value" "TPAD28"
			(at -0.0127 -1.8034 0)
			(unlocked yes)
			(layer "B.Fab")
			(hide yes)
			(effects
				(font
					(size 1.016 1.016)
					(thickness 0.1524)
				)
				(justify mirror)
			)
		)
		(property "Device Type" "TPAD28"
			(at -0.0127 -3.3274 0)
			(unlocked yes)
			(layer "B.Fab")
			(hide yes)
			(effects
				(font
					(size 1.016 1.016)
					(thickness 0.1524)
				)
				(justify mirror)
			)
		)
		(duplicate_pad_numbers_are_jumpers no)
		(fp_poly
			(pts
				(arc
					(start 0.3556 0)
					(mid -0.3556 0)
					(end 0.3556 0)
				)
			)
			(stroke
				(width 0)
				(type default)
			)
			(fill no)
			(layer "B.CrtYd")
		)
		(fp_poly
			(pts
				(arc
					(start 0.6096 0)
					(mid -0.6096 0)
					(end 0.6096 0)
				)
			)
			(stroke
				(width 0)
				(type default)
			)
			(fill no)
			(layer "B.Fab")
		)
		(pad "1" smd circle
			(at 0 0 180)
			(size 0.7112 0.7112)
			(layers "B.Cu" "B.Mask" "B.Paste")
			(net "IOC_TDO")
		)
	)
	(footprint ""
		(layer "B.Cu")
		(at 140.34897 -87.249 180)
		(property "Reference" "R175"
			(at 0 0 0)
			(layer "B.SilkS")
			(hide yes)
			(effects
				(font
					(size 1.27 1.27)
				)
				(justify mirror)
			)
		)
		(property "Value" "4K7R2F-GP"
			(at -0.064008 -3.993896 180)
			(unlocked yes)
			(layer "B.Fab")
			(hide yes)
			(effects
				(font
					(size 1.016 1.016)
					(thickness 0.1524)
				)
				(justify mirror)
			)
		)
		(property "Device Type" "R402H16"
			(at -0.064008 -5.517896 180)
			(unlocked yes)
			(layer "B.Fab")
			(hide yes)
			(effects
				(font
					(size 1.016 1.016)
					(thickness 0.1524)
				)
				(justify mirror)
			)
		)
		(duplicate_pad_numbers_are_jumpers no)
		(fp_line
			(start 0.508 -0.9398)
			(end 0.508 0.9398)
			(stroke
				(width 0.1524)
				(type default)
			)
			(layer "B.SilkS")
		)
		(fp_line
			(start -0.508 -0.9398)
			(end 0.508 -0.9398)
			(stroke
				(width 0.1524)
				(type default)
			)
			(layer "B.SilkS")
		)
		(fp_rect
			(start 0.508 0.9398)
			(end -0.508 -0.9398)
			(stroke
				(width 0)
				(type default)
			)
			(fill no)
			(layer "B.CrtYd")
		)
		(fp_rect
			(start 0.508 0.9398)
			(end -0.508 -0.9398)
			(stroke
				(width 0)
				(type default)
			)
			(fill no)
			(layer "B.Fab")
		)
		(pad "1" smd custom
			(at 0 -0.4445)
			(size 0.1397 0.1397)
			(layers "B.Cu" "B.Mask" "B.Paste")
			(net "TEMP_3_A1")
			(options
				(clearance outline)
				(anchor circle)
			)
			(primitives
				(gr_poly
					(pts
						(arc
							(start -0.1778 0.2794)
							(mid -0.249642 0.249642)
							(end -0.2794 0.1778)
						)
						(arc
							(start -0.2794 -0.1778)
							(mid -0.249642 -0.249642)
							(end -0.1778 -0.2794)
						)
						(arc
							(start 0.1778 -0.2794)
							(mid 0.249642 -0.249642)
							(end 0.2794 -0.1778)
						)
						(arc
							(start 0.2794 0.1778)
							(mid 0.249642 0.249642)
							(end 0.1778 0.2794)
						)
					)
					(width 0)
					(fill yes)
				)
			)
		)
		(pad "2" smd custom
			(at 0 0.4445)
			(size 0.1397 0.1397)
			(layers "B.Cu" "B.Mask" "B.Paste")
			(net "GND")
			(options
				(clearance outline)
				(anchor circle)
			)
			(primitives
				(gr_poly
					(pts
						(arc
							(start -0.1778 0.2794)
							(mid -0.249642 0.249642)
							(end -0.2794 0.1778)
						)
						(arc
							(start -0.2794 -0.1778)
							(mid -0.249642 -0.249642)
							(end -0.1778 -0.2794)
						)
						(arc
							(start 0.1778 -0.2794)
							(mid 0.249642 -0.249642)
							(end 0.2794 -0.1778)
						)
						(arc
							(start 0.2794 0.1778)
							(mid 0.249642 0.249642)
							(end 0.1778 0.2794)
						)
					)
					(width 0)
					(fill yes)
				)
			)
		)
	)
	(footprint ""
		(layer "B.Cu")
		(at 113.850166 -33.782)
		(property "Reference" "STP47"
			(at 0 0 0)
			(layer "B.SilkS")
			(hide yes)
			(effects
				(font
					(size 1.27 1.27)
				)
				(justify mirror)
			)
		)
		(property "Value" "TPAD28"
			(at -0.0127 -1.8034 0)
			(unlocked yes)
			(layer "B.Fab")
			(hide yes)
			(effects
				(font
					(size 1.016 1.016)
					(thickness 0.1524)
				)
				(justify mirror)
			)
		)
		(property "Device Type" "TPAD28"
			(at -0.0127 -3.3274 0)
			(unlocked yes)
			(layer "B.Fab")
			(hide yes)
			(effects
				(font
					(size 1.016 1.016)
					(thickness 0.1524)
				)
				(justify mirror)
			)
		)
		(duplicate_pad_numbers_are_jumpers no)
		(fp_poly
			(pts
				(arc
					(start 0.3556 0)
					(mid -0.3556 0)
					(end 0.3556 0)
				)
			)
			(stroke
				(width 0)
				(type default)
			)
			(fill no)
			(layer "B.CrtYd")
		)
		(fp_poly
			(pts
				(arc
					(start 0.6096 0)
					(mid -0.6096 0)
					(end 0.6096 0)
				)
			)
			(stroke
				(width 0)
				(type default)
			)
			(fill no)
			(layer "B.Fab")
		)
		(pad "1" smd circle
			(at 0 0 180)
			(size 0.7112 0.7112)
			(layers "B.Cu" "B.Mask" "B.Paste")
			(net "IOC_GPIO_10")
		)
	)
	(footprint ""
		(layer "B.Cu")
		(at 101.35997 -112.395 180)
		(property "Reference" "SC1224"
			(at 0 0 0)
			(layer "B.SilkS")
			(hide yes)
			(effects
				(font
					(size 1.27 1.27)
				)
				(justify mirror)
			)
		)
		(property "Value" "SCD1U6D3V1KX-GP"
			(at 2.8321 -1.7399 180)
			(unlocked yes)
			(layer "B.Fab")
			(hide yes)
			(effects
				(font
					(size 1.016 1.016)
					(thickness 0.1524)
				)
				(justify mirror)
			)
		)
		(property "Device Type" "C0201H13"
			(at 2.8321 -3.2639 180)
			(unlocked yes)
			(layer "B.Fab")
			(hide yes)
			(effects
				(font
					(size 1.016 1.016)
					(thickness 0.1524)
				)
				(justify mirror)
			)
		)
		(duplicate_pad_numbers_are_jumpers no)
		(fp_rect
			(start 0.2794 0.6477)
			(end -0.2794 -0.6477)
			(stroke
				(width 0)
				(type default)
			)
			(fill no)
			(layer "B.CrtYd")
		)
		(fp_rect
			(start 0.2794 0.6477)
			(end -0.2794 -0.6477)
			(stroke
				(width 0)
				(type default)
			)
			(fill no)
			(layer "B.Fab")
		)
		(pad "1" smd custom
			(at 0 -0.2794)
			(size 0.0762 0.0762)
			(layers "B.Cu" "B.Mask" "B.Paste")
			(net "P1V8_E")
			(options
				(clearance outline)
				(anchor circle)
			)
			(primitives
				(gr_poly
					(pts
						(arc
							(start 0.1524 0.127)
							(mid 0.137521 0.162921)
							(end 0.1016 0.1778)
						)
						(arc
							(start -0.1016 0.1778)
							(mid -0.137521 0.162921)
							(end -0.1524 0.127)
						)
						(arc
							(start -0.1524 -0.127)
							(mid -0.137521 -0.162921)
							(end -0.1016 -0.1778)
						)
						(arc
							(start 0.1016 -0.1778)
							(mid 0.137521 -0.162921)
							(end 0.1524 -0.127)
						)
					)
					(width 0)
					(fill yes)
				)
			)
		)
		(pad "2" smd custom
			(at 0 0.2794)
			(size 0.0762 0.0762)
			(layers "B.Cu" "B.Mask" "B.Paste")
			(net "GND")
			(options
				(clearance outline)
				(anchor circle)
			)
			(primitives
				(gr_poly
					(pts
						(arc
							(start 0.1524 0.127)
							(mid 0.137521 0.162921)
							(end 0.1016 0.1778)
						)
						(arc
							(start -0.1016 0.1778)
							(mid -0.137521 0.162921)
							(end -0.1524 0.127)
						)
						(arc
							(start -0.1524 -0.127)
							(mid -0.137521 -0.162921)
							(end -0.1016 -0.1778)
						)
						(arc
							(start 0.1016 -0.1778)
							(mid 0.137521 -0.162921)
							(end 0.1524 -0.127)
						)
					)
					(width 0)
					(fill yes)
				)
			)
		)
	)
	(footprint ""
		(layer "B.Cu")
		(at 274.193 -177.673 90)
		(property "Reference" "R340"
			(at 0 0 90)
			(layer "B.SilkS")
			(hide yes)
			(effects
				(font
					(size 1.27 1.27)
				)
				(justify mirror)
			)
		)
		(property "Value" "3K3R2F-2-GP"
			(at -0.064008 -3.993896 90)
			(unlocked yes)
			(layer "B.Fab")
			(hide yes)
			(effects
				(font
					(size 1.016 1.016)
					(thickness 0.1524)
				)
				(justify mirror)
			)
		)
		(property "Device Type" "R402H16"
			(at -0.064008 -5.517896 90)
			(unlocked yes)
			(layer "B.Fab")
			(hide yes)
			(effects
				(font
					(size 1.016 1.016)
					(thickness 0.1524)
				)
				(justify mirror)
			)
		)
		(duplicate_pad_numbers_are_jumpers no)
		(fp_line
			(start 0.508 -0.9398)
			(end 0.508 0.9398)
			(stroke
				(width 0.1524)
				(type default)
			)
			(layer "B.SilkS")
		)
		(fp_line
			(start -0.508 -0.9398)
			(end 0.508 -0.9398)
			(stroke
				(width 0.1524)
				(type default)
			)
			(layer "B.SilkS")
		)
		(fp_rect
			(start 0.508 0.9398)
			(end -0.508 -0.9398)
			(stroke
				(width 0)
				(type default)
			)
			(fill no)
			(layer "B.CrtYd")
		)
		(fp_rect
			(start 0.508 0.9398)
			(end -0.508 -0.9398)
			(stroke
				(width 0)
				(type default)
			)
			(fill no)
			(layer "B.Fab")
		)
		(pad "1" smd custom
			(at 0 -0.4445 270)
			(size 0.1397 0.1397)
			(layers "B.Cu" "B.Mask" "B.Paste")
			(net "P3V3_STBY")
			(options
				(clearance outline)
				(anchor circle)
			)
			(primitives
				(gr_poly
					(pts
						(arc
							(start -0.1778 0.2794)
							(mid -0.249642 0.249642)
							(end -0.2794 0.1778)
						)
						(arc
							(start -0.2794 -0.1778)
							(mid -0.249642 -0.249642)
							(end -0.1778 -0.2794)
						)
						(arc
							(start 0.1778 -0.2794)
							(mid 0.249642 -0.249642)
							(end 0.2794 -0.1778)
						)
						(arc
							(start 0.2794 0.1778)
							(mid 0.249642 0.249642)
							(end 0.1778 0.2794)
						)
					)
					(width 0)
					(fill yes)
				)
			)
		)
		(pad "2" smd custom
			(at 0 0.4445 270)
			(size 0.1397 0.1397)
			(layers "B.Cu" "B.Mask" "B.Paste")
			(net "ROMA8")
			(options
				(clearance outline)
				(anchor circle)
			)
			(primitives
				(gr_poly
					(pts
						(arc
							(start -0.1778 0.2794)
							(mid -0.249642 0.249642)
							(end -0.2794 0.1778)
						)
						(arc
							(start -0.2794 -0.1778)
							(mid -0.249642 -0.249642)
							(end -0.1778 -0.2794)
						)
						(arc
							(start 0.1778 -0.2794)
							(mid 0.249642 -0.249642)
							(end 0.2794 -0.1778)
						)
						(arc
							(start 0.2794 0.1778)
							(mid 0.249642 0.249642)
							(end 0.1778 0.2794)
						)
					)
					(width 0)
					(fill yes)
				)
			)
		)
	)
	(footprint ""
		(layer "B.Cu")
		(at 276.098 -162.56 -90)
		(property "Reference" "R329"
			(at 0 0 90)
			(layer "B.SilkS")
			(hide yes)
			(effects
				(font
					(size 1.27 1.27)
				)
				(justify mirror)
			)
		)
		(property "Value" "0R2J-2-GP"
			(at -0.064008 -3.993896 270)
			(unlocked yes)
			(layer "B.Fab")
			(hide yes)
			(effects
				(font
					(size 1.016 1.016)
					(thickness 0.1524)
				)
				(justify mirror)
			)
		)
		(property "Device Type" "R402H16"
			(at -0.064008 -5.517896 270)
			(unlocked yes)
			(layer "B.Fab")
			(hide yes)
			(effects
				(font
					(size 1.016 1.016)
					(thickness 0.1524)
				)
				(justify mirror)
			)
		)
		(duplicate_pad_numbers_are_jumpers no)
		(fp_line
			(start -0.508 -0.9398)
			(end 0.508 -0.9398)
			(stroke
				(width 0.1524)
				(type default)
			)
			(layer "B.SilkS")
		)
		(fp_line
			(start 0.508 -0.9398)
			(end 0.508 0.9398)
			(stroke
				(width 0.1524)
				(type default)
			)
			(layer "B.SilkS")
		)
		(fp_rect
			(start 0.508 0.9398)
			(end -0.508 -0.9398)
			(stroke
				(width 0)
				(type default)
			)
			(fill no)
			(layer "B.CrtYd")
		)
		(fp_rect
			(start 0.508 0.9398)
			(end -0.508 -0.9398)
			(stroke
				(width 0)
				(type default)
			)
			(fill no)
			(layer "B.Fab")
		)
		(pad "1" smd custom
			(at 0 -0.4445 90)
			(size 0.1397 0.1397)
			(layers "B.Cu" "B.Mask" "B.Paste")
			(net "PMU_PLTRST_N")
			(options
				(clearance outline)
				(anchor circle)
			)
			(primitives
				(gr_poly
					(pts
						(arc
							(start -0.1778 0.2794)
							(mid -0.249642 0.249642)
							(end -0.2794 0.1778)
						)
						(arc
							(start -0.2794 -0.1778)
							(mid -0.249642 -0.249642)
							(end -0.1778 -0.2794)
						)
						(arc
							(start 0.1778 -0.2794)
							(mid 0.249642 -0.249642)
							(end 0.2794 -0.1778)
						)
						(arc
							(start 0.2794 0.1778)
							(mid 0.249642 0.249642)
							(end 0.1778 0.2794)
						)
					)
					(width 0)
					(fill yes)
				)
			)
		)
		(pad "2" smd custom
			(at 0 0.4445 90)
			(size 0.1397 0.1397)
			(layers "B.Cu" "B.Mask" "B.Paste")
			(net "LPCRST0_N")
			(options
				(clearance outline)
				(anchor circle)
			)
			(primitives
				(gr_poly
					(pts
						(arc
							(start -0.1778 0.2794)
							(mid -0.249642 0.249642)
							(end -0.2794 0.1778)
						)
						(arc
							(start -0.2794 -0.1778)
							(mid -0.249642 -0.249642)
							(end -0.1778 -0.2794)
						)
						(arc
							(start 0.1778 -0.2794)
							(mid 0.249642 -0.249642)
							(end 0.2794 -0.1778)
						)
						(arc
							(start 0.2794 0.1778)
							(mid 0.249642 0.249642)
							(end 0.1778 0.2794)
						)
					)
					(width 0)
					(fill yes)
				)
			)
		)
	)
	(footprint ""
		(layer "B.Cu")
		(at 119.742966 -32.512 180)
		(property "Reference" "SC1001"
			(at 0 0 0)
			(layer "B.SilkS")
			(hide yes)
			(effects
				(font
					(size 1.27 1.27)
				)
				(justify mirror)
			)
		)
		(property "Value" "SCD1U16V2KX-3GP"
			(at -1.1811 -2.7051 180)
			(unlocked yes)
			(layer "B.Fab")
			(hide yes)
			(effects
				(font
					(size 1.016 1.016)
					(thickness 0.1524)
				)
				(justify mirror)
			)
		)
		(property "Device Type" "C402H22"
			(at -1.1811 -4.2291 180)
			(unlocked yes)
			(layer "B.Fab")
			(hide yes)
			(effects
				(font
					(size 1.016 1.016)
					(thickness 0.1524)
				)
				(justify mirror)
			)
		)
		(duplicate_pad_numbers_are_jumpers no)
		(fp_rect
			(start 0.4318 0.9525)
			(end -0.4318 -0.9525)
			(stroke
				(width 0)
				(type default)
			)
			(fill no)
			(layer "B.CrtYd")
		)
		(fp_rect
			(start 0.4318 0.9525)
			(end -0.4318 -0.9525)
			(stroke
				(width 0)
				(type default)
			)
			(fill no)
			(layer "B.Fab")
		)
		(pad "1" smd custom
			(at 0 -0.4445)
			(size 0.1524 0.1524)
			(layers "B.Cu" "B.Mask" "B.Paste")
			(net "P1V8_C")
			(options
				(clearance outline)
				(anchor circle)
			)
			(primitives
				(gr_poly
					(pts
						(arc
							(start 0.3048 0.2032)
							(mid 0.275042 0.275042)
							(end 0.2032 0.3048)
						)
						(arc
							(start -0.2032 0.3048)
							(mid -0.275042 0.275042)
							(end -0.3048 0.2032)
						)
						(arc
							(start -0.3048 -0.2032)
							(mid -0.275042 -0.275042)
							(end -0.2032 -0.3048)
						)
						(arc
							(start 0.2032 -0.3048)
							(mid 0.275042 -0.275042)
							(end 0.3048 -0.2032)
						)
					)
					(width 0)
					(fill yes)
				)
			)
		)
		(pad "2" smd custom
			(at 0 0.4445)
			(size 0.1524 0.1524)
			(layers "B.Cu" "B.Mask" "B.Paste")
			(net "GND")
			(options
				(clearance outline)
				(anchor circle)
			)
			(primitives
				(gr_poly
					(pts
						(arc
							(start 0.3048 0.2032)
							(mid 0.275042 0.275042)
							(end 0.2032 0.3048)
						)
						(arc
							(start -0.2032 0.3048)
							(mid -0.275042 0.275042)
							(end -0.3048 0.2032)
						)
						(arc
							(start -0.3048 -0.2032)
							(mid -0.275042 -0.275042)
							(end -0.2032 -0.3048)
						)
						(arc
							(start 0.2032 -0.3048)
							(mid 0.275042 -0.275042)
							(end 0.3048 -0.2032)
						)
					)
					(width 0)
					(fill yes)
				)
			)
		)
	)
	(footprint ""
		(layer "B.Cu")
		(at 293.1922 -204.343 180)
		(property "Reference" "C171"
			(at 0 0 0)
			(layer "B.SilkS")
			(hide yes)
			(effects
				(font
					(size 1.27 1.27)
				)
				(justify mirror)
			)
		)
		(property "Value" "SCD1U16V2KX-3GP"
			(at -1.1811 -2.7051 180)
			(unlocked yes)
			(layer "B.Fab")
			(hide yes)
			(effects
				(font
					(size 1.016 1.016)
					(thickness 0.1524)
				)
				(justify mirror)
			)
		)
		(property "Device Type" "C402H22"
			(at -1.1811 -4.2291 180)
			(unlocked yes)
			(layer "B.Fab")
			(hide yes)
			(effects
				(font
					(size 1.016 1.016)
					(thickness 0.1524)
				)
				(justify mirror)
			)
		)
		(duplicate_pad_numbers_are_jumpers no)
		(fp_rect
			(start 0.4318 0.9525)
			(end -0.4318 -0.9525)
			(stroke
				(width 0)
				(type default)
			)
			(fill no)
			(layer "B.CrtYd")
		)
		(fp_rect
			(start 0.4318 0.9525)
			(end -0.4318 -0.9525)
			(stroke
				(width 0)
				(type default)
			)
			(fill no)
			(layer "B.Fab")
		)
		(pad "1" smd custom
			(at 0 -0.4445)
			(size 0.1524 0.1524)
			(layers "B.Cu" "B.Mask" "B.Paste")
			(net "P1V53_STBY")
			(options
				(clearance outline)
				(anchor circle)
			)
			(primitives
				(gr_poly
					(pts
						(arc
							(start 0.3048 0.2032)
							(mid 0.275042 0.275042)
							(end 0.2032 0.3048)
						)
						(arc
							(start -0.2032 0.3048)
							(mid -0.275042 0.275042)
							(end -0.3048 0.2032)
						)
						(arc
							(start -0.3048 -0.2032)
							(mid -0.275042 -0.275042)
							(end -0.2032 -0.3048)
						)
						(arc
							(start 0.2032 -0.3048)
							(mid 0.275042 -0.275042)
							(end 0.3048 -0.2032)
						)
					)
					(width 0)
					(fill yes)
				)
			)
		)
		(pad "2" smd custom
			(at 0 0.4445)
			(size 0.1524 0.1524)
			(layers "B.Cu" "B.Mask" "B.Paste")
			(net "GND")
			(options
				(clearance outline)
				(anchor circle)
			)
			(primitives
				(gr_poly
					(pts
						(arc
							(start 0.3048 0.2032)
							(mid 0.275042 0.275042)
							(end 0.2032 0.3048)
						)
						(arc
							(start -0.2032 0.3048)
							(mid -0.275042 0.275042)
							(end -0.3048 0.2032)
						)
						(arc
							(start -0.3048 -0.2032)
							(mid -0.275042 -0.275042)
							(end -0.2032 -0.3048)
						)
						(arc
							(start 0.2032 -0.3048)
							(mid 0.275042 -0.275042)
							(end 0.3048 -0.2032)
						)
					)
					(width 0)
					(fill yes)
				)
			)
		)
	)
)
